(kicad_pcb
	(version 20241229)
	(generator "pcbnew")
	(generator_version "9.0")
	(general
		(thickness 1.62)
		(legacy_teardrops no)
	)
	(paper "A3")
	(title_block
		(title "COM Express 7 Baseboard")
		(date "2025-02-04")
		(rev "1.1.2")
		(company "Antmicro Ltd")
		(comment 1 "www.antmicro.com")
		(comment 9 "footprints 683-686 of 802")
	)
	(layers
		(0 "F.Cu" signal)
		(4 "In1.Cu" signal)
		(6 "In2.Cu" signal)
		(8 "In3.Cu" signal)
		(10 "In4.Cu" signal)
		(12 "In5.Cu" signal)
		(14 "In6.Cu" signal)
		(2 "B.Cu" signal)
		(9 "F.Adhes" user "F.Adhesive")
		(11 "B.Adhes" user "B.Adhesive")
		(13 "F.Paste" user)
		(15 "B.Paste" user)
		(5 "F.SilkS" user "F.Silkscreen")
		(7 "B.SilkS" user "B.Silkscreen")
		(1 "F.Mask" user)
		(3 "B.Mask" user)
		(17 "Dwgs.User" user "User.Drawings")
		(19 "Cmts.User" user "User.Comments")
		(21 "Eco1.User" user "User.Eco1")
		(23 "Eco2.User" user "User.Eco2")
		(25 "Edge.Cuts" user)
		(27 "Margin" user)
		(31 "F.CrtYd" user "F.Courtyard")
		(29 "B.CrtYd" user "B.Courtyard")
		(35 "F.Fab" user)
		(33 "B.Fab" user)
	)
	(footprint "antmicro-footprints:SOT-23-3"
		(layer "B.Cu")
		(at 97.75 71.86 90)
		(property "Reference" "Q8"
			(at 0.95 0.45 180)
			(layer "B.SilkS")
			(effects
				(font
					(size 0.7 0.7)
					(thickness 0.15)
				)
				(justify right bottom mirror)
			)
		)
		(property "Value" "BSS138-7-F"
			(at -1.9 -2.7 90)
			(layer "B.Fab")
			(effects
				(font
					(size 0.7 0.7)
					(thickness 0.15)
				)
				(justify right bottom mirror)
			)
		)
		(property "Datasheet" "https://www.diodes.com/assets/Datasheets/ds30144.pdf"
			(at 0 0 90)
			(layer "F.Fab")
			(hide yes)
			(effects
				(font
					(size 1.27 1.27)
					(thickness 0.15)
				)
			)
		)
		(property "Author" "Antmicro"
			(at 169.61 -25.89 0)
			(layer "B.Fab")
			(hide yes)
			(effects
				(font
					(size 1 1)
					(thickness 0.15)
				)
				(justify mirror)
			)
		)
		(property "License" "Apache-2.0"
			(at 169.61 -25.89 0)
			(layer "B.Fab")
			(hide yes)
			(effects
				(font
					(size 1 1)
					(thickness 0.15)
				)
				(justify mirror)
			)
		)
		(property "MPN" "BSS138-7-F"
			(at 169.61 -25.89 0)
			(layer "B.Fab")
			(hide yes)
			(effects
				(font
					(size 1 1)
					(thickness 0.15)
				)
				(justify mirror)
			)
		)
		(property "Manufacturer" "Diodes Incorporated"
			(at 169.61 -25.89 0)
			(layer "B.Fab")
			(hide yes)
			(effects
				(font
					(size 1 1)
					(thickness 0.15)
				)
				(justify mirror)
			)
		)
		(sheetname "Misc")
		(sheetfile "misc.kicad_sch")
		(attr smd)
		(fp_line
			(start 0.7 -1.5)
			(end 0.7 -0.4)
			(stroke
				(width 0.15)
				(type solid)
			)
			(layer "B.SilkS")
		)
		(fp_line
			(start -0.7 -1.5)
			(end 0.7 -1.5)
			(stroke
				(width 0.15)
				(type solid)
			)
			(layer "B.SilkS")
		)
		(fp_line
			(start -0.7 -1.35)
			(end -0.7 -1.5)
			(stroke
				(width 0.15)
				(type solid)
			)
			(layer "B.SilkS")
		)
		(fp_line
			(start -0.85 1.35)
			(end -1.45 1.35)
			(stroke
				(width 0.15)
				(type solid)
			)
			(layer "B.SilkS")
		)
		(fp_line
			(start 0.7 1.5)
			(end 0.7 0.4)
			(stroke
				(width 0.15)
				(type solid)
			)
			(layer "B.SilkS")
		)
		(fp_line
			(start -0.7 1.5)
			(end -0.85 1.35)
			(stroke
				(width 0.15)
				(type solid)
			)
			(layer "B.SilkS")
		)
		(fp_line
			(start -0.7 1.5)
			(end 0.7 1.5)
			(stroke
				(width 0.15)
				(type solid)
			)
			(layer "B.SilkS")
		)
		(fp_line
			(start 0.85 -1.65)
			(end 0.85 -0.45)
			(stroke
				(width 0.05)
				(type solid)
			)
			(layer "B.CrtYd")
		)
		(fp_line
			(start -0.85 -1.65)
			(end 0.85 -1.65)
			(stroke
				(width 0.05)
				(type solid)
			)
			(layer "B.CrtYd")
		)
		(fp_line
			(start -0.85 -1.4)
			(end -0.85 -1.65)
			(stroke
				(width 0.05)
				(type solid)
			)
			(layer "B.CrtYd")
		)
		(fp_line
			(start -1.75 -1.4)
			(end -0.85 -1.4)
			(stroke
				(width 0.05)
				(type solid)
			)
			(layer "B.CrtYd")
		)
		(fp_line
			(start -0.85 -0.5)
			(end -1.75 -0.5)
			(stroke
				(width 0.05)
				(type solid)
			)
			(layer "B.CrtYd")
		)
		(fp_line
			(start -1.75 -0.5)
			(end -1.75 -1.4)
			(stroke
				(width 0.05)
				(type solid)
			)
			(layer "B.CrtYd")
		)
		(fp_line
			(start 1.75 -0.45)
			(end 1.75 0.45)
			(stroke
				(width 0.05)
				(type solid)
			)
			(layer "B.CrtYd")
		)
		(fp_line
			(start 0.85 -0.45)
			(end 1.75 -0.45)
			(stroke
				(width 0.05)
				(type solid)
			)
			(layer "B.CrtYd")
		)
		(fp_line
			(start 1.75 0.45)
			(end 0.825 0.45)
			(stroke
				(width 0.05)
				(type solid)
			)
			(layer "B.CrtYd")
		)
		(fp_line
			(start 0.825 0.45)
			(end 0.825 1.6)
			(stroke
				(width 0.05)
				(type solid)
			)
			(layer "B.CrtYd")
		)
		(fp_line
			(start -0.85 0.5)
			(end -0.85 -0.5)
			(stroke
				(width 0.05)
				(type solid)
			)
			(layer "B.CrtYd")
		)
		(fp_line
			(start -1.75 0.5)
			(end -0.85 0.5)
			(stroke
				(width 0.05)
				(type solid)
			)
			(layer "B.CrtYd")
		)
		(fp_line
			(start -0.9 1.4)
			(end -0.9 1.6)
			(stroke
				(width 0.05)
				(type solid)
			)
			(layer "B.CrtYd")
		)
		(fp_line
			(start -1.75 1.4)
			(end -1.75 0.5)
			(stroke
				(width 0.05)
				(type solid)
			)
			(layer "B.CrtYd")
		)
		(fp_line
			(start -1.75 1.4)
			(end -0.9 1.4)
			(stroke
				(width 0.05)
				(type solid)
			)
			(layer "B.CrtYd")
		)
		(fp_line
			(start 0.825 1.6)
			(end -0.9 1.6)
			(stroke
				(width 0.05)
				(type solid)
			)
			(layer "B.CrtYd")
		)
		(fp_line
			(start -0.712 -1.523)
			(end -0.712 1.325)
			(stroke
				(width 0.15)
				(type solid)
			)
			(layer "B.Fab")
		)
		(fp_line
			(start 0.688 -1.519)
			(end -0.712 -1.519)
			(stroke
				(width 0.15)
				(type solid)
			)
			(layer "B.Fab")
		)
		(fp_line
			(start -0.712 1.325)
			(end -0.437 1.526)
			(stroke
				(width 0.15)
				(type solid)
			)
			(layer "B.Fab")
		)
		(fp_line
			(start 0.688 1.52)
			(end 0.688 -1.519)
			(stroke
				(width 0.15)
				(type solid)
			)
			(layer "B.Fab")
		)
		(fp_line
			(start 0.688 1.526)
			(end -0.437 1.526)
			(stroke
				(width 0.15)
				(type solid)
			)
			(layer "B.Fab")
		)
		(pad "1" smd roundrect
			(at -1.1 0.951 90)
			(size 1 0.6)
			(layers "B.Cu" "B.Mask" "B.Paste")
			(roundrect_rratio 0.15)
			(net 539 "/Misc/~{PWR_OK}")
			(pinfunction "G")
			(pintype "bidirectional")
			(teardrops
				(best_length_ratio 0.2)
				(max_length 1)
				(best_width_ratio 0.9)
				(max_width 2)
				(curved_edges yes)
				(filter_ratio 0.9)
				(enabled yes)
				(allow_two_segments yes)
				(prefer_zone_connections yes)
			)
		)
		(pad "2" smd roundrect
			(at -1.1 -0.949 90)
			(size 1 0.6)
			(layers "B.Cu" "B.Mask" "B.Paste")
			(roundrect_rratio 0.15)
			(net 1 "GND")
			(pinfunction "S")
			(pintype "bidirectional")
			(teardrops
				(best_length_ratio 0.2)
				(max_length 1)
				(best_width_ratio 0.9)
				(max_width 2)
				(curved_edges yes)
				(filter_ratio 0.9)
				(enabled yes)
				(allow_two_segments yes)
				(prefer_zone_connections yes)
			)
		)
		(pad "3" smd roundrect
			(at 1.1 0.0005 90)
			(size 1 0.6)
			(layers "B.Cu" "B.Mask" "B.Paste")
			(roundrect_rratio 0.15)
			(net 540 "Net-(Q8-D)")
			(pinfunction "D")
			(pintype "bidirectional")
			(teardrops
				(best_length_ratio 0.2)
				(max_length 1)
				(best_width_ratio 0.9)
				(max_width 2)
				(curved_edges yes)
				(filter_ratio 0.9)
				(enabled yes)
				(allow_two_segments yes)
				(prefer_zone_connections yes)
			)
		)
	)
	(footprint "antmicro-footprints:C_0402_1005Metric"
		(layer "B.Cu")
		(at 131.79 134.86)
		(descr "Capacitor SMD 0402")
		(tags "capacitor SMD 0402")
		(property "Reference" "C194"
			(at -2.99 -4.85 0)
			(layer "B.SilkS")
			(effects
				(font
					(size 0.7 0.7)
					(thickness 0.15)
				)
				(justify right bottom mirror)
			)
		)
		(property "Value" "C_100n_0402"
			(at -1.022927 -2.155213 0)
			(layer "B.Fab")
			(effects
				(font
					(size 0.7 0.7)
					(thickness 0.15)
				)
				(justify right bottom mirror)
			)
		)
		(property "Datasheet" "https://www.murata.com/products/productdetail?partno=GRM155R61H104KE14%23"
			(at 0 0 0)
			(layer "F.Fab")
			(hide yes)
			(effects
				(font
					(size 1.27 1.27)
					(thickness 0.15)
				)
			)
		)
		(property "Author" "Antmicro"
			(at 0 0 0)
			(layer "B.Fab")
			(hide yes)
			(effects
				(font
					(size 1 1)
					(thickness 0.15)
				)
				(justify mirror)
			)
		)
		(property "Dielectric" "X5R"
			(at 0 0 0)
			(layer "B.Fab")
			(hide yes)
			(effects
				(font
					(size 1 1)
					(thickness 0.15)
				)
				(justify mirror)
			)
		)
		(property "License" "Apache-2.0"
			(at 0 0 0)
			(layer "B.Fab")
			(hide yes)
			(effects
				(font
					(size 1 1)
					(thickness 0.15)
				)
				(justify mirror)
			)
		)
		(property "MPN" "GRM155R61H104KE14D"
			(at 0 0 0)
			(layer "B.Fab")
			(hide yes)
			(effects
				(font
					(size 1 1)
					(thickness 0.15)
				)
				(justify mirror)
			)
		)
		(property "Manufacturer" "Murata"
			(at 0 0 0)
			(layer "B.Fab")
			(hide yes)
			(effects
				(font
					(size 1 1)
					(thickness 0.15)
				)
				(justify mirror)
			)
		)
		(property "Public" "False"
			(at 0 0 0)
			(layer "B.Fab")
			(hide yes)
			(effects
				(font
					(size 1 1)
					(thickness 0.15)
				)
				(justify mirror)
			)
		)
		(property "Val" "100n"
			(at 0 0 0)
			(layer "B.Fab")
			(hide yes)
			(effects
				(font
					(size 1 1)
					(thickness 0.15)
				)
				(justify mirror)
			)
		)
		(property "Voltage" "50V"
			(at 0 0 0)
			(layer "B.Fab")
			(hide yes)
			(effects
				(font
					(size 1 1)
					(thickness 0.15)
				)
				(justify mirror)
			)
		)
		(sheetname "KR to SFI #2")
		(sheetfile "kr_sfi.kicad_sch")
		(attr smd)
		(fp_rect
			(start -0.925 0.47)
			(end 0.925 -0.47)
			(stroke
				(width 0.05)
				(type default)
			)
			(fill no)
			(layer "B.CrtYd")
		)
		(fp_line
			(start -0.494 -0.248)
			(end 0.504 -0.248)
			(stroke
				(width 0.15)
				(type solid)
			)
			(layer "B.Fab")
		)
		(fp_line
			(start -0.494 0.25)
			(end -0.494 -0.248)
			(stroke
				(width 0.15)
				(type solid)
			)
			(layer "B.Fab")
		)
		(fp_line
			(start 0.504 -0.248)
			(end 0.504 0.25)
			(stroke
				(width 0.15)
				(type solid)
			)
			(layer "B.Fab")
		)
		(fp_line
			(start 0.504 0.25)
			(end -0.494 0.25)
			(stroke
				(width 0.15)
				(type solid)
			)
			(layer "B.Fab")
		)
		(pad "1" smd roundrect
			(at -0.48 0)
			(size 0.59 0.64)
			(layers "B.Cu" "B.Mask" "B.Paste")
			(roundrect_rratio 0.25)
			(net 1 "GND")
			(pintype "passive")
			(teardrops
				(best_length_ratio 0.2)
				(max_length 1)
				(best_width_ratio 0.9)
				(max_width 2)
				(curved_edges yes)
				(filter_ratio 0.9)
				(enabled yes)
				(allow_two_segments yes)
				(prefer_zone_connections yes)
			)
		)
		(pad "2" smd roundrect
			(at 0.48 0)
			(size 0.59 0.64)
			(layers "B.Cu" "B.Mask" "B.Paste")
			(roundrect_rratio 0.25)
			(net 74 "+1V0")
			(pintype "passive")
			(teardrops
				(best_length_ratio 0.2)
				(max_length 1)
				(best_width_ratio 0.9)
				(max_width 2)
				(curved_edges yes)
				(filter_ratio 0.9)
				(enabled yes)
				(allow_two_segments yes)
				(prefer_zone_connections yes)
			)
		)
	)
	(footprint "antmicro-footprints:TP_SMD_0.75mm"
		(layer "B.Cu")
		(at 184.25 149.1 180)
		(property "Reference" "TP21"
			(at -3.25 -0.4 0)
			(layer "B.SilkS")
			(effects
				(font
					(size 0.7 0.7)
					(thickness 0.15)
				)
				(justify left bottom mirror)
			)
		)
		(property "Value" "TP_0.75mm_SMD"
			(at 3.225 -53.865 0)
			(layer "B.Fab")
			(hide yes)
			(effects
				(font
					(size 0.7 0.7)
					(thickness 0.15)
				)
				(justify left bottom mirror)
			)
		)
		(property "Author" "Antmicro"
			(at 444.9 333.72 0)
			(layer "B.Fab")
			(hide yes)
			(effects
				(font
					(size 1 1)
					(thickness 0.15)
				)
				(justify mirror)
			)
		)
		(property "License" "Apache-2.0"
			(at 444.9 333.72 0)
			(layer "B.Fab")
			(hide yes)
			(effects
				(font
					(size 1 1)
					(thickness 0.15)
				)
				(justify mirror)
			)
		)
		(property "MPN" ""
			(at 444.9 333.72 0)
			(layer "B.Fab")
			(hide yes)
			(effects
				(font
					(size 1 1)
					(thickness 0.15)
				)
				(justify mirror)
			)
		)
		(property "Manufacturer" ""
			(at 444.9 333.72 0)
			(layer "B.Fab")
			(hide yes)
			(effects
				(font
					(size 1 1)
					(thickness 0.15)
				)
				(justify mirror)
			)
		)
		(property "Public" "False"
			(at 444.9 333.72 0)
			(layer "B.Fab")
			(hide yes)
			(effects
				(font
					(size 1 1)
					(thickness 0.15)
				)
				(justify mirror)
			)
		)
		(sheetname "Com Express 7 Interfaces")
		(sheetfile "com_express_7_interfaces.kicad_sch")
		(attr exclude_from_pos_files exclude_from_bom)
		(fp_circle
			(center 0 0)
			(end 0.475 0)
			(stroke
				(width 0.05)
				(type default)
			)
			(fill no)
			(layer "B.CrtYd")
		)
		(pad "1" smd circle
			(at 0 0 180)
			(size 0.75 0.75)
			(layers "B.Cu" "B.Mask")
			(net 471 "Net-(J12K-10G_SDP3)")
			(pinfunction "1")
			(pintype "passive")
			(teardrops
				(best_length_ratio 0.4)
				(max_length 1)
				(best_width_ratio 0.9)
				(max_width 2)
				(curved_edges yes)
				(filter_ratio 0.9)
				(enabled yes)
				(allow_two_segments yes)
				(prefer_zone_connections yes)
			)
		)
	)
	(footprint "antmicro-footprints:C_0402_1005Metric"
		(layer "B.Cu")
		(at 198.560696 137.023438 135)
		(descr "Capacitor SMD 0402")
		(tags "capacitor SMD 0402")
		(property "Reference" "C126"
			(at -2.768935 -0.026345 135)
			(layer "B.SilkS")
			(effects
				(font
					(size 0.7 0.7)
					(thickness 0.15)
				)
				(justify right bottom mirror)
			)
		)
		(property "Value" "C_220n_0402"
			(at -1.022927 -2.155213 135)
			(layer "B.Fab")
			(effects
				(font
					(size 0.7 0.7)
					(thickness 0.15)
				)
				(justify right bottom mirror)
			)
		)
		(property "Datasheet" "https://www.yageo.com/en/Chart/Download/pdf/CC0402KRX5R6BB224"
			(at 0 0 135)
			(layer "F.Fab")
			(hide yes)
			(effects
				(font
					(size 1.27 1.27)
					(thickness 0.15)
				)
			)
		)
		(property "Author" "Antmicro"
			(at 336.71 -36.089999 45)
			(layer "B.Fab")
			(hide yes)
			(effects
				(font
					(size 1 1)
					(thickness 0.15)
				)
				(justify mirror)
			)
		)
		(property "Dielectric" ""
			(at 336.71 -36.089999 45)
			(layer "B.Fab")
			(hide yes)
			(effects
				(font
					(size 1 1)
					(thickness 0.15)
				)
				(justify mirror)
			)
		)
		(property "License" "Apache-2.0"
			(at 336.71 -36.089999 45)
			(layer "B.Fab")
			(hide yes)
			(effects
				(font
					(size 1 1)
					(thickness 0.15)
				)
				(justify mirror)
			)
		)
		(property "MPN" "CC0402KRX5R6BB224"
			(at 336.71 -36.089999 45)
			(layer "B.Fab")
			(hide yes)
			(effects
				(font
					(size 1 1)
					(thickness 0.15)
				)
				(justify mirror)
			)
		)
		(property "Manufacturer" "YAGEO"
			(at 336.71 -36.089999 45)
			(layer "B.Fab")
			(hide yes)
			(effects
				(font
					(size 1 1)
					(thickness 0.15)
				)
				(justify mirror)
			)
		)
		(property "Public" "False"
			(at 336.71 -36.089999 45)
			(layer "B.Fab")
			(hide yes)
			(effects
				(font
					(size 1 1)
					(thickness 0.15)
				)
				(justify mirror)
			)
		)
		(property "Val" "220n"
			(at 336.71 -36.089999 45)
			(layer "B.Fab")
			(hide yes)
			(effects
				(font
					(size 1 1)
					(thickness 0.15)
				)
				(justify mirror)
			)
		)
		(property "Voltage" ""
			(at 336.71 -36.089999 45)
			(layer "B.Fab")
			(hide yes)
			(effects
				(font
					(size 1 1)
					(thickness 0.15)
				)
				(justify mirror)
			)
		)
		(sheetname "PCIe redriver")
		(sheetfile "pcie_redriver.kicad_sch")
		(attr smd)
		(fp_poly
			(pts
				(xy -0.925 0.47) (xy 0.925 0.47) (xy 0.925 -0.47) (xy -0.925 -0.47)
			)
			(stroke
				(width 0.05)
				(type default)
			)
			(fill no)
			(layer "B.CrtYd")
		)
		(fp_line
			(start 0.504 -0.248)
			(end 0.504 0.25)
			(stroke
				(width 0.15)
				(type solid)
			)
			(layer "B.Fab")
		)
		(fp_line
			(start 0.504 0.25)
			(end -0.494 0.25)
			(stroke
				(width 0.15)
				(type solid)
			)
			(layer "B.Fab")
		)
		(fp_line
			(start -0.494 -0.248)
			(end 0.504 -0.248)
			(stroke
				(width 0.15)
				(type solid)
			)
			(layer "B.Fab")
		)
		(fp_line
			(start -0.494 0.25)
			(end -0.494 -0.248)
			(stroke
				(width 0.15)
				(type solid)
			)
			(layer "B.Fab")
		)
		(pad "1" smd roundrect
			(at -0.48 0 135)
			(size 0.59 0.64)
			(layers "B.Cu" "B.Mask" "B.Paste")
			(roundrect_rratio 0.25)
			(net 221 "/Com Express 7 Interfaces/PCIe_{B1x4}.RX0-")
			(pintype "passive")
			(teardrops
				(best_length_ratio 0.2)
				(max_length 1)
				(best_width_ratio 0.9)
				(max_width 2)
				(curved_edges yes)
				(filter_ratio 0.9)
				(enabled yes)
				(allow_two_segments yes)
				(prefer_zone_connections yes)
			)
		)
		(pad "2" smd roundrect
			(at 0.48 0 135)
			(size 0.59 0.64)
			(layers "B.Cu" "B.Mask" "B.Paste")
			(roundrect_rratio 0.25)
			(net 101 "/PCIe redriver/PCIe_{I}_C.RX0-")
			(pintype "passive")
			(teardrops
				(best_length_ratio 0.2)
				(max_length 1)
				(best_width_ratio 0.9)
				(max_width 2)
				(curved_edges yes)
				(filter_ratio 0.9)
				(enabled yes)
				(allow_two_segments yes)
				(prefer_zone_connections yes)
			)
		)
	)
)
